# BASEBOARD_FAB2 (Tioga Pass) — schematic netlist excerpt (pin names and nets, part order shuffled) for the footprints in the layout excerpt that follows; sources: Cadence DE-HDL packaged netlist, KiCad conversion of Wiwynn_Tioga_Pass_MB.brd

C8E5  CAP_A  0.1UF 16V 10% X7R  pkg 0402V  page 142 : A = P3V3_STBY ; B = GND
R3L4  RES  0.0 5% CHIP  pkg 0402  page 236 : A = VR_P1V05_PCH_STBY_PH1_VCIN ; B = P5V_STBY
C3M39  CAP_A  1.0UF 6.3V 10% X6S  pkg 0402V  page 131 : A = P1V05_PCH_STBY ; B = GND

(kicad_pcb
	(version 20260206)
	(generator "pcbnew")
	(generator_version "10.0")
	(general
		(thickness 1.6)
		(legacy_teardrops no)
	)
	(paper "A4")
	(title_block
		(title "Wiwynn_Tioga_Pass_MB.brd")
		(comment 1 "Tioga Pass / footprints 3771-3773 of 4770")
	)
	(layers
		(0 "F.Cu" signal "TOP")
		(4 "In1.Cu" signal "L2GND")
		(6 "In2.Cu" signal "L3")
		(8 "In3.Cu" signal "L4GND")
		(10 "In4.Cu" signal "L5")
		(12 "In5.Cu" signal "L6GND")
		(14 "In6.Cu" signal "L7VCC")
		(16 "In7.Cu" signal "L8VCC")
		(18 "In8.Cu" signal "L9GND")
		(20 "In9.Cu" signal "L10")
		(22 "In10.Cu" signal "L11GND")
		(24 "In11.Cu" signal "L12")
		(26 "In12.Cu" signal "L13GND")
		(2 "B.Cu" signal "BOTTOM")
		(9 "F.Adhes" user "F.Adhesive")
		(11 "B.Adhes" user "B.Adhesive")
		(13 "F.Paste" user "Package Geometry/Pastemask Top")
		(15 "B.Paste" user "Package Geometry/Pastemask Bottom")
		(5 "F.SilkS" user "Ref Des/Silkscreen Top")
		(7 "B.SilkS" user "Ref Des/Silkscreen Bottom")
		(1 "F.Mask" user "Board Geometry/Soldermask Top")
		(3 "B.Mask" user "Board Geometry/Soldermask Bottom")
		(17 "Dwgs.User" user "User.Drawings")
		(19 "Cmts.User" user "User.Comments")
		(21 "Eco1.User" user "User.Eco1")
		(23 "Eco2.User" user "User.Eco2")
		(25 "Edge.Cuts" user "Board Geometry/Outline")
		(27 "Margin" user)
		(31 "F.CrtYd" user "Package Geometry/Place Bound Top")
		(29 "B.CrtYd" user "Package Geometry/Place Bound Bottom")
		(35 "F.Fab" user "Ref Des/Assembly Top")
		(33 "B.Fab" user "Ref Des/Assembly Bottom")
	)
	(footprint ""
		(layer "B.Cu")
		(at 383.019808 -155.432506)
		(property "Reference" "R3L4"
			(at 0 0 0)
			(layer "B.SilkS")
			(hide yes)
			(effects
				(font
					(size 1.27 1.27)
				)
				(justify mirror)
			)
		)
		(property "Value" ""
			(at 0 0 0)
			(layer "B.Fab")
			(effects
				(font
					(size 1.27 1.27)
				)
				(justify mirror)
			)
		)
		(duplicate_pad_numbers_are_jumpers no)
		(fp_poly
			(pts
				(xy 0.2794 -0.1016) (xy -0.2794 -0.1016) (xy -0.2794 0.9906) (xy 0.2794 0.9906)
			)
			(stroke
				(width 0)
				(type default)
			)
			(fill no)
			(layer "B.CrtYd")
		)
		(fp_line
			(start -0.2794 -0.1016)
			(end 0.2794 -0.1016)
			(stroke
				(width 0.1)
				(type default)
			)
			(layer "B.Fab")
		)
		(fp_line
			(start -0.2794 0.9906)
			(end -0.2794 -0.1016)
			(stroke
				(width 0.1)
				(type default)
			)
			(layer "B.Fab")
		)
		(fp_line
			(start 0.2794 -0.1016)
			(end 0.2794 0.9906)
			(stroke
				(width 0.1)
				(type default)
			)
			(layer "B.Fab")
		)
		(fp_line
			(start 0.2794 0.9906)
			(end -0.2794 0.9906)
			(stroke
				(width 0.1)
				(type default)
			)
			(layer "B.Fab")
		)
		(pad "1" smd rect
			(at 0 0 180)
			(size 0.508 0.508)
			(layers "B.Cu" "B.Mask" "B.Paste")
			(net "VR_P1V05_PCH_STBY_PH1_VCIN")
		)
		(pad "2" smd rect
			(at 0 0.889 180)
			(size 0.508 0.508)
			(layers "B.Cu" "B.Mask" "B.Paste")
			(net "P5V_STBY")
		)
		(zone
			(layer "B.Cu")
			(hatch none 0.5)
			(connect_pads
				(clearance 0)
			)
			(min_thickness 0.25)
			(keepout
				(tracks allowed)
				(vias not_allowed)
				(pads allowed)
				(copperpour not_allowed)
				(footprints allowed)
			)
			(placement
				(enabled no)
				(sheetname "")
			)
			(fill
				(thermal_gap 0.5)
				(thermal_bridge_width 0.5)
				(island_removal_mode 0)
			)
			(polygon
				(pts
					(xy 383.273808 -155.178506) (xy 382.765808 -155.178506) (xy 382.765808 -154.797506) (xy 383.273808 -154.797506)
				)
			)
		)
		(zone
			(layer "B.Cu")
			(hatch none 0.5)
			(connect_pads
				(clearance 0)
			)
			(min_thickness 0.25)
			(keepout
				(tracks not_allowed)
				(vias allowed)
				(pads allowed)
				(copperpour not_allowed)
				(footprints allowed)
			)
			(placement
				(enabled no)
				(sheetname "")
			)
			(fill
				(thermal_gap 0.5)
				(thermal_bridge_width 0.5)
				(island_removal_mode 0)
			)
			(polygon
				(pts
					(xy 383.273808 -154.797506) (xy 382.765808 -154.797506) (xy 382.765808 -155.178506) (xy 383.273808 -155.178506)
				)
			)
		)
	)
	(footprint ""
		(layer "B.Cu")
		(at 382.7272 -114.554 180)
		(property "Reference" "C3M39"
			(at 0 0 0)
			(layer "B.SilkS")
			(hide yes)
			(effects
				(font
					(size 1.27 1.27)
				)
				(justify mirror)
			)
		)
		(property "Value" ""
			(at 0 0 0)
			(layer "B.Fab")
			(effects
				(font
					(size 1.27 1.27)
				)
				(justify mirror)
			)
		)
		(duplicate_pad_numbers_are_jumpers no)
		(fp_poly
			(pts
				(xy -0.3048 -0.1016) (xy -0.3048 0.9906) (xy 0.3048 0.9906) (xy 0.3048 -0.1016)
			)
			(stroke
				(width 0)
				(type default)
			)
			(fill no)
			(layer "B.CrtYd")
		)
		(fp_line
			(start 0.3048 0.9906)
			(end -0.3048 0.9906)
			(stroke
				(width 0.1)
				(type default)
			)
			(layer "B.Fab")
		)
		(fp_line
			(start 0.3048 -0.1016)
			(end 0.3048 0.9906)
			(stroke
				(width 0.1)
				(type default)
			)
			(layer "B.Fab")
		)
		(fp_line
			(start -0.3048 0.9906)
			(end -0.3048 -0.1016)
			(stroke
				(width 0.1)
				(type default)
			)
			(layer "B.Fab")
		)
		(fp_line
			(start -0.3048 -0.1016)
			(end 0.3048 -0.1016)
			(stroke
				(width 0.1)
				(type default)
			)
			(layer "B.Fab")
		)
		(pad "1" smd rect
			(at 0 0)
			(size 0.508 0.508)
			(layers "B.Cu" "B.Mask" "B.Paste")
			(net "P1V05_PCH_STBY")
		)
		(pad "2" smd rect
			(at 0 0.889)
			(size 0.508 0.508)
			(layers "B.Cu" "B.Mask" "B.Paste")
			(net "GND")
		)
		(zone
			(layer "B.Cu")
			(hatch none 0.5)
			(connect_pads
				(clearance 0)
			)
			(min_thickness 0.25)
			(keepout
				(tracks not_allowed)
				(vias allowed)
				(pads allowed)
				(copperpour not_allowed)
				(footprints allowed)
			)
			(placement
				(enabled no)
				(sheetname "")
			)
			(fill
				(thermal_gap 0.5)
				(thermal_bridge_width 0.5)
				(island_removal_mode 0)
			)
			(polygon
				(pts
					(xy 382.4732 -115.189) (xy 382.9812 -115.189) (xy 382.9812 -114.808) (xy 382.4732 -114.808)
				)
			)
		)
		(zone
			(layer "B.Cu")
			(hatch none 0.5)
			(connect_pads
				(clearance 0)
			)
			(min_thickness 0.25)
			(keepout
				(tracks allowed)
				(vias not_allowed)
				(pads allowed)
				(copperpour not_allowed)
				(footprints allowed)
			)
			(placement
				(enabled no)
				(sheetname "")
			)
			(fill
				(thermal_gap 0.5)
				(thermal_bridge_width 0.5)
				(island_removal_mode 0)
			)
			(polygon
				(pts
					(xy 382.4732 -114.808) (xy 382.9812 -114.808) (xy 382.9812 -115.189) (xy 382.4732 -115.189)
				)
			)
		)
	)
	(footprint ""
		(layer "B.Cu")
		(at 480.037902 -54.339998)
		(property "Reference" "C8E5"
			(at 0 0 0)
			(layer "B.SilkS")
			(hide yes)
			(effects
				(font
					(size 1.27 1.27)
				)
				(justify mirror)
			)
		)
		(property "Value" ""
			(at 0 0 0)
			(layer "B.Fab")
			(effects
				(font
					(size 1.27 1.27)
				)
				(justify mirror)
			)
		)
		(duplicate_pad_numbers_are_jumpers no)
		(fp_poly
			(pts
				(xy -0.3048 -0.1016) (xy -0.3048 0.9906) (xy 0.3048 0.9906) (xy 0.3048 -0.1016)
			)
			(stroke
				(width 0)
				(type default)
			)
			(fill no)
			(layer "B.CrtYd")
		)
		(fp_line
			(start -0.3048 -0.1016)
			(end 0.3048 -0.1016)
			(stroke
				(width 0.1)
				(type default)
			)
			(layer "B.Fab")
		)
		(fp_line
			(start -0.3048 0.9906)
			(end -0.3048 -0.1016)
			(stroke
				(width 0.1)
				(type default)
			)
			(layer "B.Fab")
		)
		(fp_line
			(start 0.3048 -0.1016)
			(end 0.3048 0.9906)
			(stroke
				(width 0.1)
				(type default)
			)
			(layer "B.Fab")
		)
		(fp_line
			(start 0.3048 0.9906)
			(end -0.3048 0.9906)
			(stroke
				(width 0.1)
				(type default)
			)
			(layer "B.Fab")
		)
		(pad "1" smd rect
			(at 0 0 180)
			(size 0.508 0.508)
			(layers "B.Cu" "B.Mask" "B.Paste")
			(net "P3V3_STBY")
		)
		(pad "2" smd rect
			(at 0 0.889 180)
			(size 0.508 0.508)
			(layers "B.Cu" "B.Mask" "B.Paste")
			(net "GND")
		)
		(zone
			(layer "B.Cu")
			(hatch none 0.5)
			(connect_pads
				(clearance 0)
			)
			(min_thickness 0.25)
			(keepout
				(tracks allowed)
				(vias not_allowed)
				(pads allowed)
				(copperpour not_allowed)
				(footprints allowed)
			)
			(placement
				(enabled no)
				(sheetname "")
			)
			(fill
				(thermal_gap 0.5)
				(thermal_bridge_width 0.5)
				(island_removal_mode 0)
			)
			(polygon
				(pts
					(xy 480.291902 -54.085998) (xy 479.783902 -54.085998) (xy 479.783902 -53.704998) (xy 480.291902 -53.704998)
				)
			)
		)
		(zone
			(layer "B.Cu")
			(hatch none 0.5)
			(connect_pads
				(clearance 0)
			)
			(min_thickness 0.25)
			(keepout
				(tracks not_allowed)
				(vias allowed)
				(pads allowed)
				(copperpour not_allowed)
				(footprints allowed)
			)
			(placement
				(enabled no)
				(sheetname "")
			)
			(fill
				(thermal_gap 0.5)
				(thermal_bridge_width 0.5)
				(island_removal_mode 0)
			)
			(polygon
				(pts
					(xy 480.291902 -53.704998) (xy 479.783902 -53.704998) (xy 479.783902 -54.085998) (xy 480.291902 -54.085998)
				)
			)
		)
	)
)
